# BASEBOARD_FAB2 (Tioga Pass) — schematic netlist excerpt (pin names and nets, part order shuffled) for the footprints in the layout excerpt that follows; sources: Cadence DE-HDL packaged netlist, KiCad conversion of Wiwynn_Tioga_Pass_MB.brd

C22W22  SC22U16V5MX-4-GP  20%  pkg SMD-BCG5  page 236 : \1\ = VR_FET_SW_P12V_STBY_PVDDQ_DEF ; \2\ = GND

J8D4  PIN-CON3-27-GP  pkg CONN-G7  page 201
  \1\  = SMB_VR_STBY_LVC3_SDA
  \2\  = GND
  \3\  = SMB_VR_STBY_LVC3_SCL

C5A9  CAP_A  47UF 4V 20% X5R  pkg 0603V  page 220 : A = PVDDQ_DEF ; B = GND

(kicad_pcb
	(version 20260206)
	(generator "pcbnew")
	(generator_version "10.0")
	(general
		(thickness 1.6)
		(legacy_teardrops no)
	)
	(paper "A4")
	(title_block
		(title "Wiwynn_Tioga_Pass_MB.brd")
		(comment 1 "Tioga Pass / footprints 891-893 of 4770")
	)
	(layers
		(0 "F.Cu" signal "TOP")
		(4 "In1.Cu" signal "L2GND")
		(6 "In2.Cu" signal "L3")
		(8 "In3.Cu" signal "L4GND")
		(10 "In4.Cu" signal "L5")
		(12 "In5.Cu" signal "L6GND")
		(14 "In6.Cu" signal "L7VCC")
		(16 "In7.Cu" signal "L8VCC")
		(18 "In8.Cu" signal "L9GND")
		(20 "In9.Cu" signal "L10")
		(22 "In10.Cu" signal "L11GND")
		(24 "In11.Cu" signal "L12")
		(26 "In12.Cu" signal "L13GND")
		(2 "B.Cu" signal "BOTTOM")
		(9 "F.Adhes" user "F.Adhesive")
		(11 "B.Adhes" user "B.Adhesive")
		(13 "F.Paste" user "Package Geometry/Pastemask Top")
		(15 "B.Paste" user "Package Geometry/Pastemask Bottom")
		(5 "F.SilkS" user "Ref Des/Silkscreen Top")
		(7 "B.SilkS" user "Ref Des/Silkscreen Bottom")
		(1 "F.Mask" user "Board Geometry/Soldermask Top")
		(3 "B.Mask" user "Board Geometry/Soldermask Bottom")
		(17 "Dwgs.User" user "User.Drawings")
		(19 "Cmts.User" user "User.Comments")
		(21 "Eco1.User" user "User.Eco1")
		(23 "Eco2.User" user "User.Eco2")
		(25 "Edge.Cuts" user "Board Geometry/Outline")
		(27 "Margin" user)
		(31 "F.CrtYd" user "Package Geometry/Place Bound Top")
		(29 "B.CrtYd" user "Package Geometry/Place Bound Bottom")
		(35 "F.Fab" user "Ref Des/Assembly Top")
		(33 "B.Fab" user "Ref Des/Assembly Bottom")
	)
	(footprint ""
		(layer "F.Cu")
		(at 462.19491 -157.140402 180)
		(property "Reference" "J8D4"
			(at 0 0 180)
			(layer "F.SilkS")
			(hide yes)
			(effects
				(font
					(size 1.27 1.27)
				)
			)
		)
		(property "Value" "*"
			(at -5.103876 -0.820166 180)
			(unlocked yes)
			(layer "F.Fab")
			(hide yes)
			(effects
				(font
					(size 1.27 1.016)
					(thickness 0.1524)
				)
			)
		)
		(property "Device Type" "PIN-CON3-27-GP_CONN-G7-PIN-CONA"
			(at -5.103876 -2.344166 180)
			(unlocked yes)
			(layer "F.Fab")
			(hide yes)
			(effects
				(font
					(size 1.27 1.016)
					(thickness 0.1524)
				)
			)
		)
		(duplicate_pad_numbers_are_jumpers no)
		(fp_line
			(start 3.937 1.4986)
			(end -3.937 1.4986)
			(stroke
				(width 0.1524)
				(type default)
			)
			(layer "F.SilkS")
		)
		(fp_line
			(start 3.937 -1.4986)
			(end 3.937 1.4986)
			(stroke
				(width 0.1524)
				(type default)
			)
			(layer "F.SilkS")
		)
		(fp_line
			(start -2.794 -1.6256)
			(end -4.064 -1.6256)
			(stroke
				(width 0.4064)
				(type default)
			)
			(layer "F.SilkS")
		)
		(fp_line
			(start -3.937 1.4986)
			(end -3.937 -1.4986)
			(stroke
				(width 0.1524)
				(type default)
			)
			(layer "F.SilkS")
		)
		(fp_line
			(start -3.937 -1.4986)
			(end 3.937 -1.4986)
			(stroke
				(width 0.1524)
				(type default)
			)
			(layer "F.SilkS")
		)
		(fp_line
			(start -4.064 -1.6256)
			(end -4.064 -0.3556)
			(stroke
				(width 0.4064)
				(type default)
			)
			(layer "F.SilkS")
		)
		(fp_circle
			(center 2.54 0)
			(end 1.4732 0)
			(stroke
				(width 0.3048)
				(type default)
			)
			(fill no)
			(layer "F.SilkS")
		)
		(fp_circle
			(center 0 0)
			(end -1.0668 0)
			(stroke
				(width 0.3048)
				(type default)
			)
			(fill no)
			(layer "F.SilkS")
		)
		(fp_circle
			(center -2.54 0)
			(end -3.6068 0)
			(stroke
				(width 0.3048)
				(type default)
			)
			(fill no)
			(layer "F.SilkS")
		)
		(fp_rect
			(start -3.683 1.2446)
			(end 3.683 -1.2446)
			(stroke
				(width 0)
				(type default)
			)
			(fill no)
			(layer "F.CrtYd")
		)
		(fp_poly
			(pts
				(xy -4.191 1.7526) (xy -4.191 -1.7526) (xy 4.191 -1.7526) (xy 4.191 1.7526) (xy 0.00254 1.7526)
				(xy 0.00254 1.2446) (xy 3.683 1.2446) (xy 3.683 -1.2446) (xy -3.683 -1.2446) (xy -3.683 1.2446)
				(xy -0.00254 1.2446) (xy -0.00254 1.7526)
			)
			(stroke
				(width 0)
				(type default)
			)
			(fill no)
			(layer "F.CrtYd")
		)
		(fp_rect
			(start -4.191 1.7526)
			(end 4.191 -1.7526)
			(stroke
				(width 0)
				(type default)
			)
			(fill no)
			(layer "F.Fab")
		)
		(pad "1" thru_hole circle
			(at -2.54 0 180)
			(size 1.4224 1.4224)
			(drill 1.016)
			(layers "*.Cu" "*.Mask")
			(remove_unused_layers no)
			(net "SMB_VR_STBY_LVC3_SDA")
			(clearance 0.1524)
			(thermal_gap 0.1524)
		)
		(pad "2" thru_hole circle
			(at 0 0 180)
			(size 1.4224 1.4224)
			(drill 1.016)
			(layers "*.Cu" "*.Mask")
			(remove_unused_layers no)
			(net "GND")
			(clearance 0.1524)
			(thermal_gap 0.1524)
		)
		(pad "3" thru_hole circle
			(at 2.54 0 180)
			(size 1.4224 1.4224)
			(drill 1.016)
			(layers "*.Cu" "*.Mask")
			(remove_unused_layers no)
			(net "SMB_VR_STBY_LVC3_SCL")
			(clearance 0.1524)
			(thermal_gap 0.1524)
		)
	)
	(footprint ""
		(layer "F.Cu")
		(at 276.000464 -149.8092 90)
		(property "Reference" "C5A9"
			(at 1.848866 0.752348 90)
			(unlocked yes)
			(layer "F.SilkS")
			(effects
				(font
					(size 1.27 0.9652)
					(thickness 0.1524)
				)
			)
		)
		(property "Value" ""
			(at 0 0 90)
			(layer "F.Fab")
			(effects
				(font
					(size 1.27 1.27)
				)
			)
		)
		(duplicate_pad_numbers_are_jumpers no)
		(fp_rect
			(start -0.500126 1.598422)
			(end 0.500126 -0.201422)
			(stroke
				(width 0)
				(type default)
			)
			(fill no)
			(layer "F.CrtYd")
		)
		(fp_line
			(start 0.500126 -0.201422)
			(end 0.500126 1.598422)
			(stroke
				(width 0.1)
				(type default)
			)
			(layer "F.Fab")
		)
		(fp_line
			(start -0.500126 -0.201422)
			(end 0.500126 -0.201422)
			(stroke
				(width 0.1)
				(type default)
			)
			(layer "F.Fab")
		)
		(fp_line
			(start 0.500126 1.598422)
			(end -0.500126 1.598422)
			(stroke
				(width 0.1)
				(type default)
			)
			(layer "F.Fab")
		)
		(fp_line
			(start -0.500126 1.598422)
			(end -0.500126 -0.201422)
			(stroke
				(width 0.1)
				(type default)
			)
			(layer "F.Fab")
		)
		(pad "1" smd rect
			(at 0 0)
			(size 0.889 0.9906)
			(layers "F.Cu" "F.Mask" "F.Paste")
			(net "PVDDQ_DEF")
		)
		(pad "2" smd rect
			(at 0 1.397)
			(size 0.889 0.9906)
			(layers "F.Cu" "F.Mask" "F.Paste")
			(net "GND")
		)
		(zone
			(layer "F.Cu")
			(hatch none 0.5)
			(connect_pads
				(clearance 0)
			)
			(min_thickness 0.25)
			(keepout
				(tracks allowed)
				(vias not_allowed)
				(pads allowed)
				(copperpour not_allowed)
				(footprints allowed)
			)
			(placement
				(enabled no)
				(sheetname "")
			)
			(fill
				(thermal_gap 0.5)
				(thermal_bridge_width 0.5)
				(island_removal_mode 0)
			)
			(polygon
				(pts
					(xy 276.952964 -149.3139) (xy 276.952964 -150.3045) (xy 276.444964 -150.3045) (xy 276.444964 -149.3139)
				)
			)
		)
		(zone
			(layer "F.Cu")
			(hatch none 0.5)
			(connect_pads
				(clearance 0)
			)
			(min_thickness 0.25)
			(keepout
				(tracks not_allowed)
				(vias allowed)
				(pads allowed)
				(copperpour not_allowed)
				(footprints allowed)
			)
			(placement
				(enabled no)
				(sheetname "")
			)
			(fill
				(thermal_gap 0.5)
				(thermal_bridge_width 0.5)
				(island_removal_mode 0)
			)
			(polygon
				(pts
					(xy 276.952964 -149.3139) (xy 276.952964 -150.3045) (xy 276.444964 -150.3045) (xy 276.444964 -149.3139)
				)
			)
		)
	)
	(footprint ""
		(layer "F.Cu")
		(at 370.967 -152.019 90)
		(property "Reference" "C22W22"
			(at 0 0 90)
			(layer "F.SilkS")
			(hide yes)
			(effects
				(font
					(size 1.27 1.27)
				)
			)
		)
		(property "Value" "*"
			(at -0.0762 -6.2357 90)
			(unlocked yes)
			(layer "F.Fab")
			(hide yes)
			(effects
				(font
					(size 1.27 1.016)
					(thickness 0.1524)
				)
			)
		)
		(property "Device Type" "SC22U16V5MX-4-GP_SMD-BCG5-SC22A"
			(at -0.0762 -8.2677 90)
			(unlocked yes)
			(layer "F.Fab")
			(hide yes)
			(effects
				(font
					(size 1.27 1.016)
					(thickness 0.1524)
				)
			)
		)
		(duplicate_pad_numbers_are_jumpers no)
		(fp_line
			(start 0.635 0)
			(end -0.635 0)
			(stroke
				(width 0.508)
				(type default)
			)
			(layer "F.SilkS")
		)
		(fp_rect
			(start -0.9652 1.778)
			(end 0.9652 -1.778)
			(stroke
				(width 0)
				(type default)
			)
			(fill no)
			(layer "F.CrtYd")
		)
		(fp_poly
			(pts
				(xy -0.9652 -1.778) (xy 0.9652 -1.778) (xy 0.9652 1.778) (xy -0.9652 1.778)
			)
			(stroke
				(width 0)
				(type default)
			)
			(fill no)
			(layer "F.Fab")
		)
		(pad "1" smd rect
			(at 0 -0.9652 90)
			(size 1.397 1.143)
			(layers "F.Cu" "F.Mask" "F.Paste")
			(net "VR_FET_SW_P12V_STBY_PVDDQ_DEF")
		)
		(pad "2" smd rect
			(at 0 0.9652 90)
			(size 1.397 1.143)
			(layers "F.Cu" "F.Mask" "F.Paste")
			(net "GND")
		)
	)
)
